# S9S_MB_2U (Grand Teton) — schematic netlist excerpt (pin names and nets, part order shuffled) for the footprints in the layout excerpt that follows; sources: Cadence DE-HDL packaged netlist, KiCad conversion of 03242023_DA0F0TMBIJ0_F0T_Motherboard_J_brd_V01_OCP.brd

PC390  Q_CAP  0.1UF 25V 10% X7R  pkg 0402  page 296 : A = PVCCD_HV_CPU1_ISENSE_N ; B = GND
PR834  Q_RES  21.5K 1% CHIP  pkg 0402LF  page 259 : A = P3V3_AUX_ILIM ; B = GND

(kicad_pcb
	(version 20260206)
	(generator "pcbnew")
	(generator_version "10.0")
	(general
		(thickness 1.6)
		(legacy_teardrops no)
	)
	(paper "A4")
	(title_block
		(title "03242023_DA0F0TMBIJ0_F0T_Motherboard_J_brd_V01_OCP.brd")
		(comment 1 "Grand Teton / footprints 2985-2986 of 6105")
	)
	(layers
		(0 "F.Cu" signal "TOP")
		(4 "In1.Cu" signal "GND")
		(6 "In2.Cu" signal "IN1")
		(8 "In3.Cu" signal "GND1")
		(10 "In4.Cu" signal "IN2")
		(12 "In5.Cu" signal "GND2")
		(14 "In6.Cu" signal "IN3")
		(16 "In7.Cu" signal "GND3")
		(18 "In8.Cu" signal "VCC")
		(20 "In9.Cu" signal "VCC1")
		(22 "In10.Cu" signal "GND4")
		(24 "In11.Cu" signal "IN4")
		(26 "In12.Cu" signal "GND5")
		(28 "In13.Cu" signal "IN5")
		(30 "In14.Cu" signal "GND6")
		(32 "In15.Cu" signal "IN6")
		(34 "In16.Cu" signal "GND7")
		(2 "B.Cu" signal "BOTTOM")
		(9 "F.Adhes" user "F.Adhesive")
		(11 "B.Adhes" user "B.Adhesive")
		(13 "F.Paste" user "Package Geometry/Pastemask Top")
		(15 "B.Paste" user "Package Geometry/Pastemask Bottom")
		(5 "F.SilkS" user "Ref Des/Silkscreen Top")
		(7 "B.SilkS" user "Ref Des/Silkscreen Bottom")
		(1 "F.Mask" user "Board Geometry/Soldermask Top")
		(3 "B.Mask" user "Board Geometry/Soldermask Bottom")
		(17 "Dwgs.User" user "User.Drawings")
		(19 "Cmts.User" user "User.Comments")
		(21 "Eco1.User" user "User.Eco1")
		(23 "Eco2.User" user "User.Eco2")
		(25 "Edge.Cuts" user "Board Geometry/Outline")
		(27 "Margin" user)
		(31 "F.CrtYd" user "Package Geometry/Place Bound Top")
		(29 "B.CrtYd" user "Package Geometry/Place Bound Bottom")
		(35 "F.Fab" user "Ref Des/Assembly Top")
		(33 "B.Fab" user "Ref Des/Assembly Bottom")
	)
	(footprint ""
		(layer "F.Cu")
		(at 445.760602 -77.829918 90)
		(property "Reference" "PR834"
			(at 0 0 90)
			(layer "F.SilkS")
			(hide yes)
			(effects
				(font
					(size 1.27 1.27)
				)
			)
		)
		(property "Value" ""
			(at 0 0 90)
			(layer "F.Fab")
			(effects
				(font
					(size 1.27 1.27)
				)
			)
		)
		(duplicate_pad_numbers_are_jumpers no)
		(fp_line
			(start 0.7874 -0.4064)
			(end 0.7874 0.4064)
			(stroke
				(width 0.1524)
				(type default)
			)
			(layer "F.SilkS")
		)
		(fp_line
			(start -0.7874 -0.4064)
			(end 0.7874 -0.4064)
			(stroke
				(width 0.1524)
				(type default)
			)
			(layer "F.SilkS")
		)
		(fp_line
			(start 0.7874 0.4064)
			(end -0.7874 0.4064)
			(stroke
				(width 0.1524)
				(type default)
			)
			(layer "F.SilkS")
		)
		(fp_line
			(start -0.7874 0.4064)
			(end -0.7874 -0.4064)
			(stroke
				(width 0.1524)
				(type default)
			)
			(layer "F.SilkS")
		)
		(fp_line
			(start -0.12065 -0.305054)
			(end -0.12065 -0.2794)
			(stroke
				(width 0.1)
				(type default)
			)
			(layer "F.Fab")
		)
		(fp_line
			(start -0.67945 -0.305054)
			(end -0.12065 -0.305054)
			(stroke
				(width 0.1)
				(type default)
			)
			(layer "F.Fab")
		)
		(fp_line
			(start 0.67945 -0.3048)
			(end 0.67945 0.3048)
			(stroke
				(width 0.1)
				(type default)
			)
			(layer "F.Fab")
		)
		(fp_line
			(start 0.12065 -0.3048)
			(end 0.67945 -0.3048)
			(stroke
				(width 0.1)
				(type default)
			)
			(layer "F.Fab")
		)
		(fp_line
			(start 0.12065 -0.2794)
			(end 0.12065 -0.3048)
			(stroke
				(width 0.1)
				(type default)
			)
			(layer "F.Fab")
		)
		(fp_line
			(start -0.12065 -0.2794)
			(end 0.12065 -0.2794)
			(stroke
				(width 0.1)
				(type default)
			)
			(layer "F.Fab")
		)
		(fp_line
			(start 0.120396 0.2794)
			(end -0.12065 0.2794)
			(stroke
				(width 0.1)
				(type default)
			)
			(layer "F.Fab")
		)
		(fp_line
			(start -0.12065 0.2794)
			(end -0.12065 0.3048)
			(stroke
				(width 0.1)
				(type default)
			)
			(layer "F.Fab")
		)
		(fp_line
			(start 0.67945 0.3048)
			(end 0.120396 0.3048)
			(stroke
				(width 0.1)
				(type default)
			)
			(layer "F.Fab")
		)
		(fp_line
			(start 0.120396 0.3048)
			(end 0.120396 0.2794)
			(stroke
				(width 0.1)
				(type default)
			)
			(layer "F.Fab")
		)
		(fp_line
			(start -0.12065 0.3048)
			(end -0.67945 0.3048)
			(stroke
				(width 0.1)
				(type default)
			)
			(layer "F.Fab")
		)
		(fp_line
			(start -0.67945 0.3048)
			(end -0.67945 -0.305054)
			(stroke
				(width 0.1)
				(type default)
			)
			(layer "F.Fab")
		)
		(pad "1" smd circle
			(at -0.40005 0 90)
			(size 0 0)
			(layers "F.Cu" "F.Mask" "F.Paste")
			(net "P3V3_AUX_ILIM")
		)
		(pad "2" smd circle
			(at 0.40005 0 90)
			(size 0 0)
			(layers "F.Cu" "F.Mask" "F.Paste")
			(net "GND")
		)
	)
	(footprint ""
		(layer "F.Cu")
		(at 32.191452 -166.777162)
		(property "Reference" "PC390"
			(at 0 0 0)
			(layer "F.SilkS")
			(hide yes)
			(effects
				(font
					(size 1.27 1.27)
				)
			)
		)
		(property "Value" ""
			(at 0 0 0)
			(layer "F.Fab")
			(effects
				(font
					(size 1.27 1.27)
				)
			)
		)
		(duplicate_pad_numbers_are_jumpers no)
		(fp_line
			(start -0.7874 -0.4064)
			(end 0.7874 -0.4064)
			(stroke
				(width 0.1524)
				(type default)
			)
			(layer "F.SilkS")
		)
		(fp_line
			(start -0.7874 0.4064)
			(end -0.7874 -0.4064)
			(stroke
				(width 0.1524)
				(type default)
			)
			(layer "F.SilkS")
		)
		(fp_line
			(start 0.7874 -0.4064)
			(end 0.7874 0.4064)
			(stroke
				(width 0.1524)
				(type default)
			)
			(layer "F.SilkS")
		)
		(fp_line
			(start 0.7874 0.4064)
			(end -0.7874 0.4064)
			(stroke
				(width 0.1524)
				(type default)
			)
			(layer "F.SilkS")
		)
		(fp_line
			(start -0.67945 -0.305054)
			(end -0.12065 -0.305054)
			(stroke
				(width 0.1)
				(type default)
			)
			(layer "F.Fab")
		)
		(fp_line
			(start -0.67945 0.3048)
			(end -0.67945 -0.305054)
			(stroke
				(width 0.1)
				(type default)
			)
			(layer "F.Fab")
		)
		(fp_line
			(start -0.12065 -0.305054)
			(end -0.12065 -0.2794)
			(stroke
				(width 0.1)
				(type default)
			)
			(layer "F.Fab")
		)
		(fp_line
			(start -0.12065 -0.2794)
			(end 0.12065 -0.2794)
			(stroke
				(width 0.1)
				(type default)
			)
			(layer "F.Fab")
		)
		(fp_line
			(start -0.12065 0.2794)
			(end -0.12065 0.3048)
			(stroke
				(width 0.1)
				(type default)
			)
			(layer "F.Fab")
		)
		(fp_line
			(start -0.12065 0.3048)
			(end -0.67945 0.3048)
			(stroke
				(width 0.1)
				(type default)
			)
			(layer "F.Fab")
		)
		(fp_line
			(start 0.120396 0.2794)
			(end -0.12065 0.2794)
			(stroke
				(width 0.1)
				(type default)
			)
			(layer "F.Fab")
		)
		(fp_line
			(start 0.120396 0.3048)
			(end 0.120396 0.2794)
			(stroke
				(width 0.1)
				(type default)
			)
			(layer "F.Fab")
		)
		(fp_line
			(start 0.12065 -0.3048)
			(end 0.67945 -0.3048)
			(stroke
				(width 0.1)
				(type default)
			)
			(layer "F.Fab")
		)
		(fp_line
			(start 0.12065 -0.2794)
			(end 0.12065 -0.3048)
			(stroke
				(width 0.1)
				(type default)
			)
			(layer "F.Fab")
		)
		(fp_line
			(start 0.67945 -0.3048)
			(end 0.67945 0.3048)
			(stroke
				(width 0.1)
				(type default)
			)
			(layer "F.Fab")
		)
		(fp_line
			(start 0.67945 0.3048)
			(end 0.120396 0.3048)
			(stroke
				(width 0.1)
				(type default)
			)
			(layer "F.Fab")
		)
		(pad "1" smd circle
			(at -0.40005 0)
			(size 0 0)
			(layers "F.Cu" "F.Mask" "F.Paste")
			(net "PVCCD_HV_CPU1_ISENSE_N")
		)
		(pad "2" smd circle
			(at 0.40005 0)
			(size 0 0)
			(layers "F.Cu" "F.Mask" "F.Paste")
			(net "GND")
		)
	)
)
